# T6G (Grand Teton) — schematic netlist excerpt (pin names and nets, part order shuffled) for the footprints in the layout excerpt that follows; sources: Cadence DE-HDL packaged netlist, KiCad conversion of 04192023_DAF0TMB3IC0_F0TG_MB_C_brd_V02_OCP.brd

C1010  Q_CAP  0.1UF 10V 10% X7S  pkg C0201  page 312 : A = P0V9_CPU0_RT3_2A ; B = GND
R188  Q_RES  0 5% CHIP  pkg 0402LF  page 82 : A = FM_BMC_READY_N ; B = FM_BMC_READY_R_N
C374  Q_CAP  1UF 4V 20% X6S  pkg 0201  page 345 : A = P1V8_CPU1_RT2_1A ; B = GND

(kicad_pcb
	(version 20260206)
	(generator "pcbnew")
	(generator_version "10.0")
	(general
		(thickness 1.6)
		(legacy_teardrops no)
	)
	(paper "A4")
	(title_block
		(title "04192023_DAF0TMB3IC0_F0TG_MB_C_brd_V02_OCP.brd")
		(comment 1 "Grand Teton / footprints 7535-7537 of 8354")
	)
	(layers
		(0 "F.Cu" signal "TOP")
		(4 "In1.Cu" signal "GND")
		(6 "In2.Cu" signal "IN1")
		(8 "In3.Cu" signal "GND1")
		(10 "In4.Cu" signal "IN2")
		(12 "In5.Cu" signal "GND2")
		(14 "In6.Cu" signal "IN3")
		(16 "In7.Cu" signal "GND3")
		(18 "In8.Cu" signal "VCC")
		(20 "In9.Cu" signal "VCC1")
		(22 "In10.Cu" signal "GND4")
		(24 "In11.Cu" signal "IN4")
		(26 "In12.Cu" signal "GND5")
		(28 "In13.Cu" signal "IN5")
		(30 "In14.Cu" signal "GND6")
		(32 "In15.Cu" signal "IN6")
		(34 "In16.Cu" signal "GND7")
		(2 "B.Cu" signal "BOTTOM")
		(9 "F.Adhes" user "F.Adhesive")
		(11 "B.Adhes" user "B.Adhesive")
		(13 "F.Paste" user "Package Geometry/Pastemask Top")
		(15 "B.Paste" user "Package Geometry/Pastemask Bottom")
		(5 "F.SilkS" user "Ref Des/Silkscreen Top")
		(7 "B.SilkS" user "Ref Des/Silkscreen Bottom")
		(1 "F.Mask" user "Board Geometry/Soldermask Top")
		(3 "B.Mask" user "Board Geometry/Soldermask Bottom")
		(17 "Dwgs.User" user "User.Drawings")
		(19 "Cmts.User" user "User.Comments")
		(21 "Eco1.User" user "User.Eco1")
		(23 "Eco2.User" user "User.Eco2")
		(25 "Edge.Cuts" user "Board Geometry/Outline")
		(27 "Margin" user)
		(31 "F.CrtYd" user "Package Geometry/Place Bound Top")
		(29 "B.CrtYd" user "Package Geometry/Place Bound Bottom")
		(35 "F.Fab" user "Ref Des/Assembly Top")
		(33 "B.Fab" user "Ref Des/Assembly Bottom")
	)
	(footprint ""
		(layer "B.Cu")
		(at 387.41858 -396.393162 -90)
		(property "Reference" "C1010"
			(at 0 0 90)
			(layer "B.SilkS")
			(hide yes)
			(effects
				(font
					(size 1.27 1.27)
				)
				(justify mirror)
			)
		)
		(property "Value" ""
			(at 0 0 90)
			(layer "B.Fab")
			(effects
				(font
					(size 1.27 1.27)
				)
				(justify mirror)
			)
		)
		(duplicate_pad_numbers_are_jumpers no)
		(fp_line
			(start -0.299974 0.150114)
			(end 0.299974 0.150114)
			(stroke
				(width 0.1)
				(type default)
			)
			(layer "B.Fab")
		)
		(fp_line
			(start 0.299974 0.150114)
			(end 0.299974 -0.150114)
			(stroke
				(width 0.1)
				(type default)
			)
			(layer "B.Fab")
		)
		(fp_line
			(start -0.299974 -0.150114)
			(end -0.299974 0.150114)
			(stroke
				(width 0.1)
				(type default)
			)
			(layer "B.Fab")
		)
		(fp_line
			(start 0.299974 -0.150114)
			(end -0.299974 -0.150114)
			(stroke
				(width 0.1)
				(type default)
			)
			(layer "B.Fab")
		)
		(pad "1" smd rect
			(at 0.2667 0 90)
			(size 0.3048 0.381)
			(layers "B.Cu" "B.Mask" "B.Paste")
			(net "P0V9_CPU0_RT3_2A")
		)
		(pad "2" smd rect
			(at -0.2667 0 90)
			(size 0.3048 0.381)
			(layers "B.Cu" "B.Mask" "B.Paste")
			(net "GND")
		)
	)
	(footprint ""
		(layer "B.Cu")
		(at 154.346148 -388.011162 -90)
		(property "Reference" "C374"
			(at 0 0 90)
			(layer "B.SilkS")
			(hide yes)
			(effects
				(font
					(size 1.27 1.27)
				)
				(justify mirror)
			)
		)
		(property "Value" ""
			(at 0 0 90)
			(layer "B.Fab")
			(effects
				(font
					(size 1.27 1.27)
				)
				(justify mirror)
			)
		)
		(duplicate_pad_numbers_are_jumpers no)
		(fp_line
			(start -0.299974 0.150114)
			(end 0.299974 0.150114)
			(stroke
				(width 0.1)
				(type default)
			)
			(layer "B.Fab")
		)
		(fp_line
			(start 0.299974 0.150114)
			(end 0.299974 -0.150114)
			(stroke
				(width 0.1)
				(type default)
			)
			(layer "B.Fab")
		)
		(fp_line
			(start -0.299974 -0.150114)
			(end -0.299974 0.150114)
			(stroke
				(width 0.1)
				(type default)
			)
			(layer "B.Fab")
		)
		(fp_line
			(start 0.299974 -0.150114)
			(end -0.299974 -0.150114)
			(stroke
				(width 0.1)
				(type default)
			)
			(layer "B.Fab")
		)
		(pad "1" smd rect
			(at 0.2667 0 90)
			(size 0.3048 0.381)
			(layers "B.Cu" "B.Mask" "B.Paste")
			(net "P1V8_CPU1_RT2_1A")
		)
		(pad "2" smd rect
			(at -0.2667 0 90)
			(size 0.3048 0.381)
			(layers "B.Cu" "B.Mask" "B.Paste")
			(net "GND")
		)
	)
	(footprint ""
		(layer "B.Cu")
		(at 176.657 -100.294948 -90)
		(property "Reference" "R188"
			(at 0 0 90)
			(layer "B.SilkS")
			(hide yes)
			(effects
				(font
					(size 1.27 1.27)
				)
				(justify mirror)
			)
		)
		(property "Value" ""
			(at 0 0 90)
			(layer "B.Fab")
			(effects
				(font
					(size 1.27 1.27)
				)
				(justify mirror)
			)
		)
		(duplicate_pad_numbers_are_jumpers no)
		(fp_line
			(start -0.7874 0.4064)
			(end 0.7874 0.4064)
			(stroke
				(width 0.1524)
				(type default)
			)
			(layer "B.SilkS")
		)
		(fp_line
			(start 0.7874 0.4064)
			(end 0.7874 -0.4064)
			(stroke
				(width 0.1524)
				(type default)
			)
			(layer "B.SilkS")
		)
		(fp_line
			(start -0.7874 -0.4064)
			(end -0.7874 0.4064)
			(stroke
				(width 0.1524)
				(type default)
			)
			(layer "B.SilkS")
		)
		(fp_line
			(start 0.7874 -0.4064)
			(end -0.7874 -0.4064)
			(stroke
				(width 0.1524)
				(type default)
			)
			(layer "B.SilkS")
		)
		(fp_line
			(start -0.67945 0.3048)
			(end -0.120396 0.3048)
			(stroke
				(width 0.1)
				(type default)
			)
			(layer "B.Fab")
		)
		(fp_line
			(start -0.120396 0.3048)
			(end -0.120396 0.2794)
			(stroke
				(width 0.1)
				(type default)
			)
			(layer "B.Fab")
		)
		(fp_line
			(start 0.12065 0.3048)
			(end 0.67945 0.3048)
			(stroke
				(width 0.1)
				(type default)
			)
			(layer "B.Fab")
		)
		(fp_line
			(start 0.67945 0.3048)
			(end 0.67945 -0.305054)
			(stroke
				(width 0.1)
				(type default)
			)
			(layer "B.Fab")
		)
		(fp_line
			(start -0.120396 0.2794)
			(end 0.12065 0.2794)
			(stroke
				(width 0.1)
				(type default)
			)
			(layer "B.Fab")
		)
		(fp_line
			(start 0.12065 0.2794)
			(end 0.12065 0.3048)
			(stroke
				(width 0.1)
				(type default)
			)
			(layer "B.Fab")
		)
		(fp_line
			(start -0.12065 -0.2794)
			(end -0.12065 -0.3048)
			(stroke
				(width 0.1)
				(type default)
			)
			(layer "B.Fab")
		)
		(fp_line
			(start 0.12065 -0.2794)
			(end -0.12065 -0.2794)
			(stroke
				(width 0.1)
				(type default)
			)
			(layer "B.Fab")
		)
		(fp_line
			(start -0.67945 -0.3048)
			(end -0.67945 0.3048)
			(stroke
				(width 0.1)
				(type default)
			)
			(layer "B.Fab")
		)
		(fp_line
			(start -0.12065 -0.3048)
			(end -0.67945 -0.3048)
			(stroke
				(width 0.1)
				(type default)
			)
			(layer "B.Fab")
		)
		(fp_line
			(start 0.12065 -0.305054)
			(end 0.12065 -0.2794)
			(stroke
				(width 0.1)
				(type default)
			)
			(layer "B.Fab")
		)
		(fp_line
			(start 0.67945 -0.305054)
			(end 0.12065 -0.305054)
			(stroke
				(width 0.1)
				(type default)
			)
			(layer "B.Fab")
		)
		(pad "1" smd circle
			(at 0.40005 0 90)
			(size 0 0)
			(layers "B.Cu" "B.Mask" "B.Paste")
			(net "FM_BMC_READY_N")
		)
		(pad "2" smd circle
			(at -0.40005 0 90)
			(size 0 0)
			(layers "B.Cu" "B.Mask" "B.Paste")
			(net "FM_BMC_READY_R_N")
		)
	)
)
